(kicad_pcb
	(version 20260206)
	(generator "pcbnew")
	(generator_version "10.0")
	(general
		(thickness 1.6)
		(legacy_teardrops no)
	)
	(paper "A4")
	(title_block
		(title "dpb — 14545-sa.0730WZS0815.brd")
		(comment 1 "Honey Badger (Wiwynn) / footprint 323 of 1066 (CN1), pads 94-166 of 166")
	)
	(layers
		(0 "F.Cu" signal "TOP")
		(4 "In1.Cu" signal "L2GND")
		(6 "In2.Cu" signal "L3")
		(8 "In3.Cu" signal "L4VCC")
		(10 "In4.Cu" signal "L5VCC")
		(12 "In5.Cu" signal "L6")
		(14 "In6.Cu" signal "L7GND")
		(2 "B.Cu" signal "BOTTOM")
		(9 "F.Adhes" user "F.Adhesive")
		(11 "B.Adhes" user "B.Adhesive")
		(13 "F.Paste" user "Package Geometry/Pastemask Top")
		(15 "B.Paste" user "Package Geometry/Pastemask Bottom")
		(5 "F.SilkS" user "Ref Des/Silkscreen Top")
		(7 "B.SilkS" user "Ref Des/Silkscreen Bottom")
		(1 "F.Mask" user "Board Geometry/Soldermask Top")
		(3 "B.Mask" user "Board Geometry/Soldermask Bottom")
		(17 "Dwgs.User" user "User.Drawings")
		(19 "Cmts.User" user "User.Comments")
		(21 "Eco1.User" user "User.Eco1")
		(23 "Eco2.User" user "User.Eco2")
		(25 "Edge.Cuts" user "Board Geometry/Outline")
		(27 "Margin" user)
		(31 "F.CrtYd" user "Package Geometry/Place Bound Top")
		(29 "B.CrtYd" user "Package Geometry/Place Bound Bottom")
		(35 "F.Fab" user "Ref Des/Assembly Top")
		(33 "B.Fab" user "Ref Des/Assembly Bottom")
	)
	(footprint ""
		(layer "F.Cu")
		(at 2.500122 -355.998526 -90)
		(property "Reference" "CN1"
			(at 0 0 270)
			(layer "F.SilkS")
			(hide yes)
			(effects
				(font
					(size 1.27 1.27)
				)
			)
		)
		(property "Value" "PCISLT164-70-GP"
			(at -77.8764 -6.4262 270)
			(unlocked yes)
			(layer "F.Fab")
			(hide yes)
			(effects
				(font
					(size 1.016 1.016)
					(thickness 0.1524)
				)
			)
		)
		(property "Device Type" "G630EAA12048EU"
			(at -77.8764 -7.9502 270)
			(unlocked yes)
			(layer "F.Fab")
			(hide yes)
			(effects
				(font
					(size 1.016 1.016)
					(thickness 0.1524)
				)
			)
		)
		(duplicate_pad_numbers_are_jumpers no)
		(pad "B10" smd rect
			(at 2.500122 -0.692404 270)
			(size 0.7112 3.6068)
			(layers "F.Cu" "F.Mask" "F.Paste")
			(net "GND")
		)
		(pad "B11" smd rect
			(at 1.500124 -0.692404 270)
			(size 0.7112 3.6068)
			(layers "F.Cu" "F.Mask" "F.Paste")
			(net "DPB_HW_REV")
		)
		(pad "B12" smd rect
			(at -1.500124 -0.692404 270)
			(size 0.7112 3.6068)
			(layers "F.Cu" "F.Mask" "F.Paste")
			(net "SAS2X28_A_HDD13_TX_+")
		)
		(pad "B13" smd rect
			(at -2.500376 -0.692404 270)
			(size 0.7112 3.6068)
			(layers "F.Cu" "F.Mask" "F.Paste")
			(net "SAS2X28_A_HDD13_TX_-")
		)
		(pad "B14" smd rect
			(at -3.500374 -0.692404 270)
			(size 0.7112 3.6068)
			(layers "F.Cu" "F.Mask" "F.Paste")
			(net "GND")
		)
		(pad "B15" smd rect
			(at -4.500372 -0.692404 270)
			(size 0.7112 3.6068)
			(layers "F.Cu" "F.Mask" "F.Paste")
			(net "GND")
		)
		(pad "B16" smd rect
			(at -5.50037 -0.692404 270)
			(size 0.7112 3.6068)
			(layers "F.Cu" "F.Mask" "F.Paste")
			(net "SAS2X28_A_HDD14_TX_+")
		)
		(pad "B17" smd rect
			(at -6.500368 -0.692404 270)
			(size 0.7112 3.6068)
			(layers "F.Cu" "F.Mask" "F.Paste")
			(net "SAS2X28_A_HDD14_TX_-")
		)
		(pad "B18" smd rect
			(at -7.500366 -0.692404 270)
			(size 0.7112 3.6068)
			(layers "F.Cu" "F.Mask" "F.Paste")
			(net "GND")
		)
		(pad "B19" smd rect
			(at -8.500364 -0.692404 270)
			(size 0.7112 3.6068)
			(layers "F.Cu" "F.Mask" "F.Paste")
			(net "GND")
		)
		(pad "B20" smd rect
			(at -9.500362 -0.692404 270)
			(size 0.7112 3.6068)
			(layers "F.Cu" "F.Mask" "F.Paste")
			(net "SAS2X28_A_HDD9_TX_+")
		)
		(pad "B21" smd rect
			(at -10.50036 -0.692404 270)
			(size 0.7112 3.6068)
			(layers "F.Cu" "F.Mask" "F.Paste")
			(net "SAS2X28_A_HDD9_TX_-")
		)
		(pad "B22" smd rect
			(at -11.500358 -0.692404 270)
			(size 0.7112 3.6068)
			(layers "F.Cu" "F.Mask" "F.Paste")
			(net "GND")
		)
		(pad "B23" smd rect
			(at -12.500356 -0.692404 270)
			(size 0.7112 3.6068)
			(layers "F.Cu" "F.Mask" "F.Paste")
			(net "GND")
		)
		(pad "B24" smd rect
			(at -13.500354 -0.692404 270)
			(size 0.7112 3.6068)
			(layers "F.Cu" "F.Mask" "F.Paste")
			(net "SAS2X28_A_HDD8_TX_+")
		)
		(pad "B25" smd rect
			(at -14.500352 -0.692404 270)
			(size 0.7112 3.6068)
			(layers "F.Cu" "F.Mask" "F.Paste")
			(net "SAS2X28_A_HDD8_TX_-")
		)
		(pad "B26" smd rect
			(at -15.50035 -0.692404 270)
			(size 0.7112 3.6068)
			(layers "F.Cu" "F.Mask" "F.Paste")
			(net "GND")
		)
		(pad "B27" smd rect
			(at -16.500348 -0.692404 270)
			(size 0.7112 3.6068)
			(layers "F.Cu" "F.Mask" "F.Paste")
			(net "GND")
		)
		(pad "B28" smd rect
			(at -17.500346 -0.692404 270)
			(size 0.7112 3.6068)
			(layers "F.Cu" "F.Mask" "F.Paste")
			(net "SAS2X28_A_HDD7_TX_+")
		)
		(pad "B29" smd rect
			(at -18.500344 -0.692404 270)
			(size 0.7112 3.6068)
			(layers "F.Cu" "F.Mask" "F.Paste")
			(net "SAS2X28_A_HDD7_TX_-")
		)
		(pad "B30" smd rect
			(at -19.500342 -0.692404 270)
			(size 0.7112 3.6068)
			(layers "F.Cu" "F.Mask" "F.Paste")
			(net "GND")
		)
		(pad "B31" smd rect
			(at -20.50034 -0.692404 270)
			(size 0.7112 3.6068)
			(layers "F.Cu" "F.Mask" "F.Paste")
			(net "GND")
		)
		(pad "B32" smd rect
			(at -21.500338 -0.692404 270)
			(size 0.7112 3.6068)
			(layers "F.Cu" "F.Mask" "F.Paste")
			(net "SAS2X28_A_HDD4_TX_+")
		)
		(pad "B33" smd rect
			(at -22.500336 -0.692404 270)
			(size 0.7112 3.6068)
			(layers "F.Cu" "F.Mask" "F.Paste")
			(net "SAS2X28_A_HDD4_TX_-")
		)
		(pad "B34" smd rect
			(at -23.500334 -0.692404 270)
			(size 0.7112 3.6068)
			(layers "F.Cu" "F.Mask" "F.Paste")
			(net "GND")
		)
		(pad "B35" smd rect
			(at -24.500332 -0.692404 270)
			(size 0.7112 3.6068)
			(layers "F.Cu" "F.Mask" "F.Paste")
			(net "GND")
		)
		(pad "B36" smd rect
			(at -25.50033 -0.692404 270)
			(size 0.7112 3.6068)
			(layers "F.Cu" "F.Mask" "F.Paste")
			(net "SAS2X28_A_HDD3_TX_+")
		)
		(pad "B37" smd rect
			(at -26.500328 -0.692404 270)
			(size 0.7112 3.6068)
			(layers "F.Cu" "F.Mask" "F.Paste")
			(net "SAS2X28_A_HDD3_TX_-")
		)
		(pad "B38" smd rect
			(at -27.500326 -0.692404 270)
			(size 0.7112 3.6068)
			(layers "F.Cu" "F.Mask" "F.Paste")
			(net "GND")
		)
		(pad "B39" smd rect
			(at -28.500324 -0.692404 270)
			(size 0.7112 3.6068)
			(layers "F.Cu" "F.Mask" "F.Paste")
			(net "GND")
		)
		(pad "B40" smd rect
			(at -29.500322 -0.692404 270)
			(size 0.7112 3.6068)
			(layers "F.Cu" "F.Mask" "F.Paste")
			(net "SAS2X28_A_HDD6_TX_+")
		)
		(pad "B41" smd rect
			(at -30.50032 -0.692404 270)
			(size 0.7112 3.6068)
			(layers "F.Cu" "F.Mask" "F.Paste")
			(net "SAS2X28_A_HDD6_TX_-")
		)
		(pad "B42" smd rect
			(at -31.500318 -0.692404 270)
			(size 0.7112 3.6068)
			(layers "F.Cu" "F.Mask" "F.Paste")
			(net "GND")
		)
		(pad "B43" smd rect
			(at -32.500316 -0.692404 270)
			(size 0.7112 3.6068)
			(layers "F.Cu" "F.Mask" "F.Paste")
			(net "SAS2X28_A_HDD6_FLT")
		)
		(pad "B44" smd rect
			(at -33.500314 -0.692404 270)
			(size 0.7112 3.6068)
			(layers "F.Cu" "F.Mask" "F.Paste")
			(net "SAS2X28_A_HDD2_FLT")
		)
		(pad "B45" smd rect
			(at -34.500312 -0.692404 270)
			(size 0.7112 3.6068)
			(layers "F.Cu" "F.Mask" "F.Paste")
			(net "SAS2X28_A_HDD1_FLT")
		)
		(pad "B46" smd rect
			(at -35.50031 -0.692404 270)
			(size 0.7112 3.6068)
			(layers "F.Cu" "F.Mask" "F.Paste")
			(net "SAS2X28_A_HDD10_FLT")
		)
		(pad "B47" smd rect
			(at -36.500308 -0.692404 270)
			(size 0.7112 3.6068)
			(layers "F.Cu" "F.Mask" "F.Paste")
			(net "SAS2X28_A_HDD0_FLT")
		)
		(pad "B48" smd rect
			(at -37.500306 -0.692404 270)
			(size 0.7112 3.6068)
			(layers "F.Cu" "F.Mask" "F.Paste")
			(net "GND")
		)
		(pad "B49" smd rect
			(at -38.500304 -0.692404 270)
			(size 0.7112 3.6068)
			(layers "F.Cu" "F.Mask" "F.Paste")
			(net "SAS2X28_A_HDD2_TX_+")
		)
		(pad "B50" smd rect
			(at -39.500302 -0.692404 270)
			(size 0.7112 3.6068)
			(layers "F.Cu" "F.Mask" "F.Paste")
			(net "SAS2X28_A_HDD2_TX_-")
		)
		(pad "B51" smd rect
			(at -40.5003 -0.692404 270)
			(size 0.7112 3.6068)
			(layers "F.Cu" "F.Mask" "F.Paste")
			(net "GND")
		)
		(pad "B52" smd rect
			(at -41.500298 -0.692404 270)
			(size 0.7112 3.6068)
			(layers "F.Cu" "F.Mask" "F.Paste")
			(net "SAS2X28_A_HDD5_FLT")
		)
		(pad "B53" smd rect
			(at -42.500296 -0.692404 270)
			(size 0.7112 3.6068)
			(layers "F.Cu" "F.Mask" "F.Paste")
			(net "SAS2X28_A_HDD15_FLT")
		)
		(pad "B54" smd rect
			(at -43.500294 -0.692404 270)
			(size 0.7112 3.6068)
			(layers "F.Cu" "F.Mask" "F.Paste")
			(net "SELF_1A&2A_HB")
		)
		(pad "B55" smd rect
			(at -44.500292 -0.692404 270)
			(size 0.7112 3.6068)
			(layers "F.Cu" "F.Mask" "F.Paste")
			(net "HB_EXP_A_INPUT")
		)
		(pad "B56" smd rect
			(at -45.50029 -0.692404 270)
			(size 0.7112 3.6068)
			(layers "F.Cu" "F.Mask" "F.Paste")
			(net "I2C_B_SCL_DAMP_A")
		)
		(pad "B57" smd rect
			(at -46.500288 -0.692404 270)
			(size 0.7112 3.6068)
			(layers "F.Cu" "F.Mask" "F.Paste")
			(net "I2C_B_SDA_DAMP_A")
		)
		(pad "B58" smd rect
			(at -47.500286 -0.692404 270)
			(size 0.7112 3.6068)
			(layers "F.Cu" "F.Mask" "F.Paste")
			(net "TEMP_SENSOR_A_ADDR0&ID")
		)
		(pad "B59" smd rect
			(at -48.500284 -0.692404 270)
			(size 0.7112 3.6068)
			(layers "F.Cu" "F.Mask" "F.Paste")
			(net "PWM_EXP_A")
		)
		(pad "B60" smd rect
			(at -49.500282 -0.692404 270)
			(size 0.7112 3.6068)
			(layers "F.Cu" "F.Mask" "F.Paste")
			(net "PEER_1A&2A_HB")
		)
		(pad "B61" smd rect
			(at -50.50028 -0.692404 270)
			(size 0.7112 3.6068)
			(layers "F.Cu" "F.Mask" "F.Paste")
			(net "GND")
		)
		(pad "B62" smd rect
			(at -51.500278 -0.692404 270)
			(size 0.7112 3.6068)
			(layers "F.Cu" "F.Mask" "F.Paste")
			(net "SAS2X28_A_HDD1_TX_+")
		)
		(pad "B63" smd rect
			(at -52.500276 -0.692404 270)
			(size 0.7112 3.6068)
			(layers "F.Cu" "F.Mask" "F.Paste")
			(net "SAS2X28_A_HDD1_TX_-")
		)
		(pad "B64" smd rect
			(at -53.500274 -0.692404 270)
			(size 0.7112 3.6068)
			(layers "F.Cu" "F.Mask" "F.Paste")
			(net "GND")
		)
		(pad "B65" smd rect
			(at -54.500272 -0.692404 270)
			(size 0.7112 3.6068)
			(layers "F.Cu" "F.Mask" "F.Paste")
			(net "GND")
		)
		(pad "B66" smd rect
			(at -55.50027 -0.692404 270)
			(size 0.7112 3.6068)
			(layers "F.Cu" "F.Mask" "F.Paste")
			(net "SAS2X28_A_HDD10_TX_+")
		)
		(pad "B67" smd rect
			(at -56.500268 -0.692404 270)
			(size 0.7112 3.6068)
			(layers "F.Cu" "F.Mask" "F.Paste")
			(net "SAS2X28_A_HDD10_TX_-")
		)
		(pad "B68" smd rect
			(at -57.500266 -0.692404 270)
			(size 0.7112 3.6068)
			(layers "F.Cu" "F.Mask" "F.Paste")
			(net "GND")
		)
		(pad "B69" smd rect
			(at -58.500264 -0.692404 270)
			(size 0.7112 3.6068)
			(layers "F.Cu" "F.Mask" "F.Paste")
			(net "GND")
		)
		(pad "B70" smd rect
			(at -59.500262 -0.692404 270)
			(size 0.7112 3.6068)
			(layers "F.Cu" "F.Mask" "F.Paste")
			(net "SAS2X28_A_HDD0_TX_+")
		)
		(pad "B71" smd rect
			(at -60.50026 -0.692404 270)
			(size 0.7112 3.6068)
			(layers "F.Cu" "F.Mask" "F.Paste")
			(net "SAS2X28_A_HDD0_TX_-")
		)
		(pad "B72" smd rect
			(at -61.500258 -0.692404 270)
			(size 0.7112 3.6068)
			(layers "F.Cu" "F.Mask" "F.Paste")
			(net "GND")
		)
		(pad "B73" smd rect
			(at -62.500256 -0.692404 270)
			(size 0.7112 3.6068)
			(layers "F.Cu" "F.Mask" "F.Paste")
			(net "GND")
		)
		(pad "B74" smd rect
			(at -63.500254 -0.692404 270)
			(size 0.7112 3.6068)
			(layers "F.Cu" "F.Mask" "F.Paste")
			(net "SAS2X28_A_HDD5_TX_+")
		)
		(pad "B75" smd rect
			(at -64.500252 -0.692404 270)
			(size 0.7112 3.6068)
			(layers "F.Cu" "F.Mask" "F.Paste")
			(net "SAS2X28_A_HDD5_TX_-")
		)
		(pad "B76" smd rect
			(at -65.50025 -0.692404 270)
			(size 0.7112 3.6068)
			(layers "F.Cu" "F.Mask" "F.Paste")
			(net "GND")
		)
		(pad "B77" smd rect
			(at -66.500248 -0.692404 270)
			(size 0.7112 3.6068)
			(layers "F.Cu" "F.Mask" "F.Paste")
			(net "GND")
		)
		(pad "B78" smd rect
			(at -67.500246 -0.692404 270)
			(size 0.7112 3.6068)
			(layers "F.Cu" "F.Mask" "F.Paste")
			(net "SEB_AB_TX+")
		)
		(pad "B79" smd rect
			(at -68.500244 -0.692404 270)
			(size 0.7112 3.6068)
			(layers "F.Cu" "F.Mask" "F.Paste")
			(net "SEB_AB_TX-")
		)
		(pad "B80" smd rect
			(at -69.500242 -0.692404 270)
			(size 0.7112 3.6068)
			(layers "F.Cu" "F.Mask" "F.Paste")
			(net "GND")
		)
		(pad "B81" smd rect
			(at -70.50024 -0.692404 270)
			(size 0.7112 3.6068)
			(layers "F.Cu" "F.Mask" "F.Paste")
			(net "GND")
		)
		(pad "B82" smd rect
			(at -71.500238 -0.692404 270)
			(size 0.7112 3.6068)
			(layers "F.Cu" "F.Mask" "F.Paste")
			(net "GND")
		)
	)
)
